#ISCELL
  mstr_symbols design_note *
  *
#ISCELL
  mstr_symbols intel_corp_bpage *
  *
#ISCELL
  mstr_symbols pvddq_abc *
  page38_i11
#ISCELL
  mstr_symbols pvddq_def *
  page38_i12
#ISCELL
  mstr_symbols pvccio_cpu0 *
  page38_i14
#ISCELL
  mstr_symbols gnd *
  page38_i16
#ISCELL
  mstr_symbols pvccio_cpu0 *
  page38_i17
#CELL
  mstr_discrete cap *
  page38_i19
#ISCELL
  mstr_symbols pvsa_cpu0 *
  page38_i24
#ISCELL
  mstr_symbols vcc_core *
  page38_i25
#ISCELL
  mstr_symbols vcc_core *
  page38_i26
#ISCELL
  mstr_symbols pvpp_abc *
  page38_i31
#CELL
  chpset_lib skx_ext_b *
  page38_i33
#CELL
  chpset_lib skx_ext_b *
  page38_i34
#ISCELL
  mstr_symbols vcc_core *
  page38_i35
#ISCELL
  mstr_symbols p3v3_stby *
  page38_i36
